# T6G (Grand Teton) — schematic netlist excerpt (pin names and nets, part order shuffled) for the footprints in the layout excerpt that follows; sources: Cadence DE-HDL packaged netlist, KiCad conversion of 04192023_DAF0TMB3IC0_F0TG_MB_C_brd_V02_OCP.brd

PC6557_1  Q_CAP  22UF 16V 20% X6S  pkg C0805  page 363 : A = SW_P12V_AUX_P0V9_RETIMER_CPU0_FLT ; B = GND
R1574  Q_RES  49.9 1% CHIP  pkg 0402LF  page 92 : A = I3C_SPD_DDRGL_CPU0_SCL ; B = I3C_SPD_DDRG_CPU0_SCL
R506  Q_RES  15 1% CHIP  pkg 0402LF  page 43 : A = M_G_CPU1_ALERT_N ; B = M_G_CPU1_ALERT_R_N

(kicad_pcb
	(version 20260206)
	(generator "pcbnew")
	(generator_version "10.0")
	(general
		(thickness 1.6)
		(legacy_teardrops no)
	)
	(paper "A4")
	(title_block
		(title "04192023_DAF0TMB3IC0_F0TG_MB_C_brd_V02_OCP.brd")
		(comment 1 "Grand Teton / footprints 7762-7764 of 8354")
	)
	(layers
		(0 "F.Cu" signal "TOP")
		(4 "In1.Cu" signal "GND")
		(6 "In2.Cu" signal "IN1")
		(8 "In3.Cu" signal "GND1")
		(10 "In4.Cu" signal "IN2")
		(12 "In5.Cu" signal "GND2")
		(14 "In6.Cu" signal "IN3")
		(16 "In7.Cu" signal "GND3")
		(18 "In8.Cu" signal "VCC")
		(20 "In9.Cu" signal "VCC1")
		(22 "In10.Cu" signal "GND4")
		(24 "In11.Cu" signal "IN4")
		(26 "In12.Cu" signal "GND5")
		(28 "In13.Cu" signal "IN5")
		(30 "In14.Cu" signal "GND6")
		(32 "In15.Cu" signal "IN6")
		(34 "In16.Cu" signal "GND7")
		(2 "B.Cu" signal "BOTTOM")
		(9 "F.Adhes" user "F.Adhesive")
		(11 "B.Adhes" user "B.Adhesive")
		(13 "F.Paste" user "Package Geometry/Pastemask Top")
		(15 "B.Paste" user "Package Geometry/Pastemask Bottom")
		(5 "F.SilkS" user "Ref Des/Silkscreen Top")
		(7 "B.SilkS" user "Ref Des/Silkscreen Bottom")
		(1 "F.Mask" user "Board Geometry/Soldermask Top")
		(3 "B.Mask" user "Board Geometry/Soldermask Bottom")
		(17 "Dwgs.User" user "User.Drawings")
		(19 "Cmts.User" user "User.Comments")
		(21 "Eco1.User" user "User.Eco1")
		(23 "Eco2.User" user "User.Eco2")
		(25 "Edge.Cuts" user "Board Geometry/Outline")
		(27 "Margin" user)
		(31 "F.CrtYd" user "Package Geometry/Place Bound Top")
		(29 "B.CrtYd" user "Package Geometry/Place Bound Bottom")
		(35 "F.Fab" user "Ref Des/Assembly Top")
		(33 "B.Fab" user "Ref Des/Assembly Bottom")
	)
	(footprint ""
		(layer "B.Cu")
		(at 167.531034 -244.085364)
		(property "Reference" "R506"
			(at 0 0 0)
			(layer "B.SilkS")
			(hide yes)
			(effects
				(font
					(size 1.27 1.27)
				)
				(justify mirror)
			)
		)
		(property "Value" ""
			(at 0 0 0)
			(layer "B.Fab")
			(effects
				(font
					(size 1.27 1.27)
				)
				(justify mirror)
			)
		)
		(duplicate_pad_numbers_are_jumpers no)
		(fp_line
			(start -0.7874 -0.4064)
			(end -0.7874 0.4064)
			(stroke
				(width 0.1524)
				(type default)
			)
			(layer "B.SilkS")
		)
		(fp_line
			(start -0.7874 0.4064)
			(end 0.7874 0.4064)
			(stroke
				(width 0.1524)
				(type default)
			)
			(layer "B.SilkS")
		)
		(fp_line
			(start 0.7874 -0.4064)
			(end -0.7874 -0.4064)
			(stroke
				(width 0.1524)
				(type default)
			)
			(layer "B.SilkS")
		)
		(fp_line
			(start 0.7874 0.4064)
			(end 0.7874 -0.4064)
			(stroke
				(width 0.1524)
				(type default)
			)
			(layer "B.SilkS")
		)
		(fp_line
			(start -0.67945 -0.3048)
			(end -0.67945 0.3048)
			(stroke
				(width 0.1)
				(type default)
			)
			(layer "B.Fab")
		)
		(fp_line
			(start -0.67945 0.3048)
			(end -0.120396 0.3048)
			(stroke
				(width 0.1)
				(type default)
			)
			(layer "B.Fab")
		)
		(fp_line
			(start -0.12065 -0.3048)
			(end -0.67945 -0.3048)
			(stroke
				(width 0.1)
				(type default)
			)
			(layer "B.Fab")
		)
		(fp_line
			(start -0.12065 -0.2794)
			(end -0.12065 -0.3048)
			(stroke
				(width 0.1)
				(type default)
			)
			(layer "B.Fab")
		)
		(fp_line
			(start -0.120396 0.2794)
			(end 0.12065 0.2794)
			(stroke
				(width 0.1)
				(type default)
			)
			(layer "B.Fab")
		)
		(fp_line
			(start -0.120396 0.3048)
			(end -0.120396 0.2794)
			(stroke
				(width 0.1)
				(type default)
			)
			(layer "B.Fab")
		)
		(fp_line
			(start 0.12065 -0.305054)
			(end 0.12065 -0.2794)
			(stroke
				(width 0.1)
				(type default)
			)
			(layer "B.Fab")
		)
		(fp_line
			(start 0.12065 -0.2794)
			(end -0.12065 -0.2794)
			(stroke
				(width 0.1)
				(type default)
			)
			(layer "B.Fab")
		)
		(fp_line
			(start 0.12065 0.2794)
			(end 0.12065 0.3048)
			(stroke
				(width 0.1)
				(type default)
			)
			(layer "B.Fab")
		)
		(fp_line
			(start 0.12065 0.3048)
			(end 0.67945 0.3048)
			(stroke
				(width 0.1)
				(type default)
			)
			(layer "B.Fab")
		)
		(fp_line
			(start 0.67945 -0.305054)
			(end 0.12065 -0.305054)
			(stroke
				(width 0.1)
				(type default)
			)
			(layer "B.Fab")
		)
		(fp_line
			(start 0.67945 0.3048)
			(end 0.67945 -0.305054)
			(stroke
				(width 0.1)
				(type default)
			)
			(layer "B.Fab")
		)
		(pad "1" smd circle
			(at 0.40005 0 180)
			(size 0 0)
			(layers "B.Cu" "B.Mask" "B.Paste")
			(net "M_G_CPU1_ALERT_N")
		)
		(pad "2" smd circle
			(at -0.40005 0 180)
			(size 0 0)
			(layers "B.Cu" "B.Mask" "B.Paste")
			(net "M_G_CPU1_ALERT_R_N")
		)
	)
	(footprint ""
		(layer "B.Cu")
		(at 448.38874 -397.05407 90)
		(property "Reference" "PC6557_1"
			(at 0 0 90)
			(layer "B.SilkS")
			(hide yes)
			(effects
				(font
					(size 1.27 1.27)
				)
				(justify mirror)
			)
		)
		(property "Value" ""
			(at 0 0 90)
			(layer "B.Fab")
			(effects
				(font
					(size 1.27 1.27)
				)
				(justify mirror)
			)
		)
		(duplicate_pad_numbers_are_jumpers no)
		(fp_line
			(start 1.524 -0.762)
			(end -1.524 -0.762)
			(stroke
				(width 0.1524)
				(type default)
			)
			(layer "B.SilkS")
		)
		(fp_line
			(start -1.524 -0.762)
			(end -1.524 0.762)
			(stroke
				(width 0.1524)
				(type default)
			)
			(layer "B.SilkS")
		)
		(fp_line
			(start 1.524 0.762)
			(end 1.524 -0.762)
			(stroke
				(width 0.1524)
				(type default)
			)
			(layer "B.SilkS")
		)
		(fp_line
			(start -1.524 0.762)
			(end 1.524 0.762)
			(stroke
				(width 0.1524)
				(type default)
			)
			(layer "B.SilkS")
		)
		(fp_line
			(start 1.1049 -0.724916)
			(end 1.1049 0.724916)
			(stroke
				(width 0.1)
				(type default)
			)
			(layer "B.Fab")
		)
		(fp_line
			(start -1.1049 -0.724916)
			(end 1.1049 -0.724916)
			(stroke
				(width 0.1)
				(type default)
			)
			(layer "B.Fab")
		)
		(fp_line
			(start 1.1049 0.724916)
			(end -1.1049 0.724916)
			(stroke
				(width 0.1)
				(type default)
			)
			(layer "B.Fab")
		)
		(fp_line
			(start -1.1049 0.724916)
			(end -1.1049 -0.724916)
			(stroke
				(width 0.1)
				(type default)
			)
			(layer "B.Fab")
		)
		(pad "1" smd rect
			(at 0.889 0 90)
			(size 1.016 1.27)
			(layers "B.Cu" "B.Mask" "B.Paste")
			(net "SW_P12V_AUX_P0V9_RETIMER_CPU0_FLT")
		)
		(pad "2" smd rect
			(at -0.889 0 90)
			(size 1.016 1.27)
			(layers "B.Cu" "B.Mask" "B.Paste")
			(net "GND")
		)
	)
	(footprint ""
		(layer "B.Cu")
		(at 415.712402 -194.88531 180)
		(property "Reference" "R1574"
			(at 0 0 0)
			(layer "B.SilkS")
			(hide yes)
			(effects
				(font
					(size 1.27 1.27)
				)
				(justify mirror)
			)
		)
		(property "Value" ""
			(at 0 0 0)
			(layer "B.Fab")
			(effects
				(font
					(size 1.27 1.27)
				)
				(justify mirror)
			)
		)
		(duplicate_pad_numbers_are_jumpers no)
		(fp_line
			(start 0.7874 0.4064)
			(end 0.7874 -0.4064)
			(stroke
				(width 0.1524)
				(type default)
			)
			(layer "B.SilkS")
		)
		(fp_line
			(start 0.7874 -0.4064)
			(end -0.7874 -0.4064)
			(stroke
				(width 0.1524)
				(type default)
			)
			(layer "B.SilkS")
		)
		(fp_line
			(start -0.7874 0.4064)
			(end 0.7874 0.4064)
			(stroke
				(width 0.1524)
				(type default)
			)
			(layer "B.SilkS")
		)
		(fp_line
			(start -0.7874 -0.4064)
			(end -0.7874 0.4064)
			(stroke
				(width 0.1524)
				(type default)
			)
			(layer "B.SilkS")
		)
		(fp_line
			(start 0.67945 0.3048)
			(end 0.67945 -0.305054)
			(stroke
				(width 0.1)
				(type default)
			)
			(layer "B.Fab")
		)
		(fp_line
			(start 0.67945 -0.305054)
			(end 0.12065 -0.305054)
			(stroke
				(width 0.1)
				(type default)
			)
			(layer "B.Fab")
		)
		(fp_line
			(start 0.12065 0.3048)
			(end 0.67945 0.3048)
			(stroke
				(width 0.1)
				(type default)
			)
			(layer "B.Fab")
		)
		(fp_line
			(start 0.12065 0.2794)
			(end 0.12065 0.3048)
			(stroke
				(width 0.1)
				(type default)
			)
			(layer "B.Fab")
		)
		(fp_line
			(start 0.12065 -0.2794)
			(end -0.12065 -0.2794)
			(stroke
				(width 0.1)
				(type default)
			)
			(layer "B.Fab")
		)
		(fp_line
			(start 0.12065 -0.305054)
			(end 0.12065 -0.2794)
			(stroke
				(width 0.1)
				(type default)
			)
			(layer "B.Fab")
		)
		(fp_line
			(start -0.120396 0.3048)
			(end -0.120396 0.2794)
			(stroke
				(width 0.1)
				(type default)
			)
			(layer "B.Fab")
		)
		(fp_line
			(start -0.120396 0.2794)
			(end 0.12065 0.2794)
			(stroke
				(width 0.1)
				(type default)
			)
			(layer "B.Fab")
		)
		(fp_line
			(start -0.12065 -0.2794)
			(end -0.12065 -0.3048)
			(stroke
				(width 0.1)
				(type default)
			)
			(layer "B.Fab")
		)
		(fp_line
			(start -0.12065 -0.3048)
			(end -0.67945 -0.3048)
			(stroke
				(width 0.1)
				(type default)
			)
			(layer "B.Fab")
		)
		(fp_line
			(start -0.67945 0.3048)
			(end -0.120396 0.3048)
			(stroke
				(width 0.1)
				(type default)
			)
			(layer "B.Fab")
		)
		(fp_line
			(start -0.67945 -0.3048)
			(end -0.67945 0.3048)
			(stroke
				(width 0.1)
				(type default)
			)
			(layer "B.Fab")
		)
		(pad "1" smd circle
			(at 0.40005 0)
			(size 0 0)
			(layers "B.Cu" "B.Mask" "B.Paste")
			(net "I3C_SPD_DDRGL_CPU0_SCL")
		)
		(pad "2" smd circle
			(at -0.40005 0)
			(size 0 0)
			(layers "B.Cu" "B.Mask" "B.Paste")
			(net "I3C_SPD_DDRG_CPU0_SCL")
		)
	)
)
